# SCM (Grand Teton) — schematic netlist excerpt (pin names and nets, part order shuffled) for the footprints in the layout excerpt that follows; sources: Cadence DE-HDL packaged netlist, KiCad conversion of 12092022_DA0F0TMDCD0_F0T_Management_Board_D_brd_V3_OCP.brd

R42  Q_RES  4.7K 1% CHIP  pkg 0402LF  page 27 : A = P3V3_AUX ; B = Q7_D
R317  Q_RES  0 5% CHIP  pkg 0402LF  page 35 : A = PWR_LED_CPLD ; B = PWR_LED

(kicad_pcb
	(version 20260206)
	(generator "pcbnew")
	(generator_version "10.0")
	(general
		(thickness 1.6)
		(legacy_teardrops no)
	)
	(paper "A4")
	(title_block
		(title "12092022_DA0F0TMDCD0_F0T_Management_Board_D_brd_V3_OCP.brd")
		(comment 1 "Grand Teton / footprints 1070-1071 of 1440")
	)
	(layers
		(0 "F.Cu" signal "TOP")
		(4 "In1.Cu" signal "GND")
		(6 "In2.Cu" signal "IN1")
		(8 "In3.Cu" signal "GND1")
		(10 "In4.Cu" signal "IN2")
		(12 "In5.Cu" signal "VCC")
		(14 "In6.Cu" signal "VCC1")
		(16 "In7.Cu" signal "IN3")
		(18 "In8.Cu" signal "GND2")
		(20 "In9.Cu" signal "IN4")
		(22 "In10.Cu" signal "GND3")
		(2 "B.Cu" signal "BOTTOM")
		(9 "F.Adhes" user "F.Adhesive")
		(11 "B.Adhes" user "B.Adhesive")
		(13 "F.Paste" user "Package Geometry/Pastemask Top")
		(15 "B.Paste" user "Package Geometry/Pastemask Bottom")
		(5 "F.SilkS" user "Ref Des/Silkscreen Top")
		(7 "B.SilkS" user "Ref Des/Silkscreen Bottom")
		(1 "F.Mask" user "Board Geometry/Soldermask Top")
		(3 "B.Mask" user "Board Geometry/Soldermask Bottom")
		(17 "Dwgs.User" user "User.Drawings")
		(19 "Cmts.User" user "User.Comments")
		(21 "Eco1.User" user "User.Eco1")
		(23 "Eco2.User" user "User.Eco2")
		(25 "Edge.Cuts" user "Board Geometry/Outline")
		(27 "Margin" user)
		(31 "F.CrtYd" user "Package Geometry/Place Bound Top")
		(29 "B.CrtYd" user "Package Geometry/Place Bound Bottom")
		(35 "F.Fab" user "Ref Des/Assembly Top")
		(33 "B.Fab" user "Ref Des/Assembly Bottom")
	)
	(footprint ""
		(layer "B.Cu")
		(at 12.319 -97.536)
		(property "Reference" "R317"
			(at 0 0 0)
			(layer "B.SilkS")
			(hide yes)
			(effects
				(font
					(size 1.27 1.27)
				)
				(justify mirror)
			)
		)
		(property "Value" ""
			(at 0 0 0)
			(layer "B.Fab")
			(effects
				(font
					(size 1.27 1.27)
				)
				(justify mirror)
			)
		)
		(duplicate_pad_numbers_are_jumpers no)
		(fp_line
			(start -0.7874 -0.4064)
			(end -0.7874 0.4064)
			(stroke
				(width 0.1524)
				(type default)
			)
			(layer "B.SilkS")
		)
		(fp_line
			(start -0.7874 0.4064)
			(end 0.7874 0.4064)
			(stroke
				(width 0.1524)
				(type default)
			)
			(layer "B.SilkS")
		)
		(fp_line
			(start 0.7874 -0.4064)
			(end -0.7874 -0.4064)
			(stroke
				(width 0.1524)
				(type default)
			)
			(layer "B.SilkS")
		)
		(fp_line
			(start 0.7874 0.4064)
			(end 0.7874 -0.4064)
			(stroke
				(width 0.1524)
				(type default)
			)
			(layer "B.SilkS")
		)
		(fp_line
			(start -0.67945 -0.3048)
			(end -0.67945 0.3048)
			(stroke
				(width 0.1)
				(type default)
			)
			(layer "B.Fab")
		)
		(fp_line
			(start -0.67945 0.3048)
			(end -0.120396 0.3048)
			(stroke
				(width 0.1)
				(type default)
			)
			(layer "B.Fab")
		)
		(fp_line
			(start -0.12065 -0.3048)
			(end -0.67945 -0.3048)
			(stroke
				(width 0.1)
				(type default)
			)
			(layer "B.Fab")
		)
		(fp_line
			(start -0.12065 -0.2794)
			(end -0.12065 -0.3048)
			(stroke
				(width 0.1)
				(type default)
			)
			(layer "B.Fab")
		)
		(fp_line
			(start -0.120396 0.2794)
			(end 0.12065 0.2794)
			(stroke
				(width 0.1)
				(type default)
			)
			(layer "B.Fab")
		)
		(fp_line
			(start -0.120396 0.3048)
			(end -0.120396 0.2794)
			(stroke
				(width 0.1)
				(type default)
			)
			(layer "B.Fab")
		)
		(fp_line
			(start 0.12065 -0.305054)
			(end 0.12065 -0.2794)
			(stroke
				(width 0.1)
				(type default)
			)
			(layer "B.Fab")
		)
		(fp_line
			(start 0.12065 -0.2794)
			(end -0.12065 -0.2794)
			(stroke
				(width 0.1)
				(type default)
			)
			(layer "B.Fab")
		)
		(fp_line
			(start 0.12065 0.2794)
			(end 0.12065 0.3048)
			(stroke
				(width 0.1)
				(type default)
			)
			(layer "B.Fab")
		)
		(fp_line
			(start 0.12065 0.3048)
			(end 0.67945 0.3048)
			(stroke
				(width 0.1)
				(type default)
			)
			(layer "B.Fab")
		)
		(fp_line
			(start 0.67945 -0.305054)
			(end 0.12065 -0.305054)
			(stroke
				(width 0.1)
				(type default)
			)
			(layer "B.Fab")
		)
		(fp_line
			(start 0.67945 0.3048)
			(end 0.67945 -0.305054)
			(stroke
				(width 0.1)
				(type default)
			)
			(layer "B.Fab")
		)
		(pad "1" smd circle
			(at 0.40005 0 180)
			(size 0 0)
			(layers "B.Cu" "B.Mask" "B.Paste")
			(net "PWR_LED_CPLD")
		)
		(pad "2" smd circle
			(at -0.40005 0 180)
			(size 0 0)
			(layers "B.Cu" "B.Mask" "B.Paste")
			(net "PWR_LED")
		)
	)
	(footprint ""
		(layer "B.Cu")
		(at 74.717148 -93.358208 -90)
		(property "Reference" "R42"
			(at 0 0 90)
			(layer "B.SilkS")
			(hide yes)
			(effects
				(font
					(size 1.27 1.27)
				)
				(justify mirror)
			)
		)
		(property "Value" ""
			(at 0 0 90)
			(layer "B.Fab")
			(effects
				(font
					(size 1.27 1.27)
				)
				(justify mirror)
			)
		)
		(duplicate_pad_numbers_are_jumpers no)
		(fp_line
			(start -0.7874 0.4064)
			(end 0.7874 0.4064)
			(stroke
				(width 0.1524)
				(type default)
			)
			(layer "B.SilkS")
		)
		(fp_line
			(start 0.7874 0.4064)
			(end 0.7874 -0.4064)
			(stroke
				(width 0.1524)
				(type default)
			)
			(layer "B.SilkS")
		)
		(fp_line
			(start -0.7874 -0.4064)
			(end -0.7874 0.4064)
			(stroke
				(width 0.1524)
				(type default)
			)
			(layer "B.SilkS")
		)
		(fp_line
			(start 0.7874 -0.4064)
			(end -0.7874 -0.4064)
			(stroke
				(width 0.1524)
				(type default)
			)
			(layer "B.SilkS")
		)
		(fp_line
			(start -0.67945 0.3048)
			(end -0.120396 0.3048)
			(stroke
				(width 0.1)
				(type default)
			)
			(layer "B.Fab")
		)
		(fp_line
			(start -0.120396 0.3048)
			(end -0.120396 0.2794)
			(stroke
				(width 0.1)
				(type default)
			)
			(layer "B.Fab")
		)
		(fp_line
			(start 0.12065 0.3048)
			(end 0.67945 0.3048)
			(stroke
				(width 0.1)
				(type default)
			)
			(layer "B.Fab")
		)
		(fp_line
			(start 0.67945 0.3048)
			(end 0.67945 -0.305054)
			(stroke
				(width 0.1)
				(type default)
			)
			(layer "B.Fab")
		)
		(fp_line
			(start -0.120396 0.2794)
			(end 0.12065 0.2794)
			(stroke
				(width 0.1)
				(type default)
			)
			(layer "B.Fab")
		)
		(fp_line
			(start 0.12065 0.2794)
			(end 0.12065 0.3048)
			(stroke
				(width 0.1)
				(type default)
			)
			(layer "B.Fab")
		)
		(fp_line
			(start -0.12065 -0.2794)
			(end -0.12065 -0.3048)
			(stroke
				(width 0.1)
				(type default)
			)
			(layer "B.Fab")
		)
		(fp_line
			(start 0.12065 -0.2794)
			(end -0.12065 -0.2794)
			(stroke
				(width 0.1)
				(type default)
			)
			(layer "B.Fab")
		)
		(fp_line
			(start -0.67945 -0.3048)
			(end -0.67945 0.3048)
			(stroke
				(width 0.1)
				(type default)
			)
			(layer "B.Fab")
		)
		(fp_line
			(start -0.12065 -0.3048)
			(end -0.67945 -0.3048)
			(stroke
				(width 0.1)
				(type default)
			)
			(layer "B.Fab")
		)
		(fp_line
			(start 0.12065 -0.305054)
			(end 0.12065 -0.2794)
			(stroke
				(width 0.1)
				(type default)
			)
			(layer "B.Fab")
		)
		(fp_line
			(start 0.67945 -0.305054)
			(end 0.12065 -0.305054)
			(stroke
				(width 0.1)
				(type default)
			)
			(layer "B.Fab")
		)
		(pad "1" smd circle
			(at 0.40005 0 90)
			(size 0 0)
			(layers "B.Cu" "B.Mask" "B.Paste")
			(net "P3V3_AUX")
		)
		(pad "2" smd circle
			(at -0.40005 0 90)
			(size 0 0)
			(layers "B.Cu" "B.Mask" "B.Paste")
			(net "Q7_D")
		)
	)
)
